(kicad_pcb
	(version 20260206)
	(generator "pcbnew")
	(generator_version "10.0")
	(general
		(thickness 1.6)
		(legacy_teardrops no)
	)
	(paper "A4")
	(title_block
		(title "04192023_DAF0TMB3IC0_F0TG_MB_C_brd_V02_OCP.brd")
		(comment 1 "Grand Teton / footprints 6953-6959 of 8354")
	)
	(layers
		(0 "F.Cu" signal "TOP")
		(4 "In1.Cu" signal "GND")
		(6 "In2.Cu" signal "IN1")
		(8 "In3.Cu" signal "GND1")
		(10 "In4.Cu" signal "IN2")
		(12 "In5.Cu" signal "GND2")
		(14 "In6.Cu" signal "IN3")
		(16 "In7.Cu" signal "GND3")
		(18 "In8.Cu" signal "VCC")
		(20 "In9.Cu" signal "VCC1")
		(22 "In10.Cu" signal "GND4")
		(24 "In11.Cu" signal "IN4")
		(26 "In12.Cu" signal "GND5")
		(28 "In13.Cu" signal "IN5")
		(30 "In14.Cu" signal "GND6")
		(32 "In15.Cu" signal "IN6")
		(34 "In16.Cu" signal "GND7")
		(2 "B.Cu" signal "BOTTOM")
		(9 "F.Adhes" user "F.Adhesive")
		(11 "B.Adhes" user "B.Adhesive")
		(13 "F.Paste" user "Package Geometry/Pastemask Top")
		(15 "B.Paste" user "Package Geometry/Pastemask Bottom")
		(5 "F.SilkS" user "Ref Des/Silkscreen Top")
		(7 "B.SilkS" user "Ref Des/Silkscreen Bottom")
		(1 "F.Mask" user "Board Geometry/Soldermask Top")
		(3 "B.Mask" user "Board Geometry/Soldermask Bottom")
		(17 "Dwgs.User" user "User.Drawings")
		(19 "Cmts.User" user "User.Comments")
		(21 "Eco1.User" user "User.Eco1")
		(23 "Eco2.User" user "User.Eco2")
		(25 "Edge.Cuts" user "Board Geometry/Outline")
		(27 "Margin" user)
		(31 "F.CrtYd" user "Package Geometry/Place Bound Top")
		(29 "B.CrtYd" user "Package Geometry/Place Bound Bottom")
		(35 "F.Fab" user "Ref Des/Assembly Top")
		(33 "B.Fab" user "Ref Des/Assembly Bottom")
	)
	(footprint ""
		(layer "B.Cu")
		(at 236.20095 -50.193448 180)
		(property "Reference" "R3771"
			(at 0 0 0)
			(layer "B.SilkS")
			(hide yes)
			(effects
				(font
					(size 1.27 1.27)
				)
				(justify mirror)
			)
		)
		(property "Value" ""
			(at 0 0 0)
			(layer "B.Fab")
			(effects
				(font
					(size 1.27 1.27)
				)
				(justify mirror)
			)
		)
		(duplicate_pad_numbers_are_jumpers no)
		(fp_line
			(start 0.7874 0.4064)
			(end 0.7874 -0.4064)
			(stroke
				(width 0.1524)
				(type default)
			)
			(layer "B.SilkS")
		)
		(fp_line
			(start 0.7874 -0.4064)
			(end -0.7874 -0.4064)
			(stroke
				(width 0.1524)
				(type default)
			)
			(layer "B.SilkS")
		)
		(fp_line
			(start -0.7874 0.4064)
			(end 0.7874 0.4064)
			(stroke
				(width 0.1524)
				(type default)
			)
			(layer "B.SilkS")
		)
		(fp_line
			(start -0.7874 -0.4064)
			(end -0.7874 0.4064)
			(stroke
				(width 0.1524)
				(type default)
			)
			(layer "B.SilkS")
		)
		(fp_line
			(start 0.67945 0.3048)
			(end 0.67945 -0.305054)
			(stroke
				(width 0.1)
				(type default)
			)
			(layer "B.Fab")
		)
		(fp_line
			(start 0.67945 -0.305054)
			(end 0.12065 -0.305054)
			(stroke
				(width 0.1)
				(type default)
			)
			(layer "B.Fab")
		)
		(fp_line
			(start 0.12065 0.3048)
			(end 0.67945 0.3048)
			(stroke
				(width 0.1)
				(type default)
			)
			(layer "B.Fab")
		)
		(fp_line
			(start 0.12065 0.2794)
			(end 0.12065 0.3048)
			(stroke
				(width 0.1)
				(type default)
			)
			(layer "B.Fab")
		)
		(fp_line
			(start 0.12065 -0.2794)
			(end -0.12065 -0.2794)
			(stroke
				(width 0.1)
				(type default)
			)
			(layer "B.Fab")
		)
		(fp_line
			(start 0.12065 -0.305054)
			(end 0.12065 -0.2794)
			(stroke
				(width 0.1)
				(type default)
			)
			(layer "B.Fab")
		)
		(fp_line
			(start -0.120396 0.3048)
			(end -0.120396 0.2794)
			(stroke
				(width 0.1)
				(type default)
			)
			(layer "B.Fab")
		)
		(fp_line
			(start -0.120396 0.2794)
			(end 0.12065 0.2794)
			(stroke
				(width 0.1)
				(type default)
			)
			(layer "B.Fab")
		)
		(fp_line
			(start -0.12065 -0.2794)
			(end -0.12065 -0.3048)
			(stroke
				(width 0.1)
				(type default)
			)
			(layer "B.Fab")
		)
		(fp_line
			(start -0.12065 -0.3048)
			(end -0.67945 -0.3048)
			(stroke
				(width 0.1)
				(type default)
			)
			(layer "B.Fab")
		)
		(fp_line
			(start -0.67945 0.3048)
			(end -0.120396 0.3048)
			(stroke
				(width 0.1)
				(type default)
			)
			(layer "B.Fab")
		)
		(fp_line
			(start -0.67945 -0.3048)
			(end -0.67945 0.3048)
			(stroke
				(width 0.1)
				(type default)
			)
			(layer "B.Fab")
		)
		(pad "1" smd circle
			(at 0.40005 0)
			(size 0 0)
			(layers "B.Cu" "B.Mask" "B.Paste")
			(net "P3V3_AUX")
		)
		(pad "2" smd circle
			(at -0.40005 0)
			(size 0 0)
			(layers "B.Cu" "B.Mask" "B.Paste")
			(net "E1S_0_PWRDIS")
		)
	)
	(footprint ""
		(layer "B.Cu")
		(at 358.389174 -400.19605 180)
		(property "Reference" "C625"
			(at 0 0 0)
			(layer "B.SilkS")
			(hide yes)
			(effects
				(font
					(size 1.27 1.27)
				)
				(justify mirror)
			)
		)
		(property "Value" ""
			(at 0 0 0)
			(layer "B.Fab")
			(effects
				(font
					(size 1.27 1.27)
				)
				(justify mirror)
			)
		)
		(duplicate_pad_numbers_are_jumpers no)
		(fp_line
			(start 1.524 0.762)
			(end 1.524 -0.762)
			(stroke
				(width 0.1524)
				(type default)
			)
			(layer "B.SilkS")
		)
		(fp_line
			(start 1.524 -0.762)
			(end -1.524 -0.762)
			(stroke
				(width 0.1524)
				(type default)
			)
			(layer "B.SilkS")
		)
		(fp_line
			(start -1.524 0.762)
			(end 1.524 0.762)
			(stroke
				(width 0.1524)
				(type default)
			)
			(layer "B.SilkS")
		)
		(fp_line
			(start -1.524 -0.762)
			(end -1.524 0.762)
			(stroke
				(width 0.1524)
				(type default)
			)
			(layer "B.SilkS")
		)
		(fp_line
			(start 1.1049 0.724916)
			(end -1.1049 0.724916)
			(stroke
				(width 0.1)
				(type default)
			)
			(layer "B.Fab")
		)
		(fp_line
			(start 1.1049 -0.724916)
			(end 1.1049 0.724916)
			(stroke
				(width 0.1)
				(type default)
			)
			(layer "B.Fab")
		)
		(fp_line
			(start -1.1049 0.724916)
			(end -1.1049 -0.724916)
			(stroke
				(width 0.1)
				(type default)
			)
			(layer "B.Fab")
		)
		(fp_line
			(start -1.1049 -0.724916)
			(end 1.1049 -0.724916)
			(stroke
				(width 0.1)
				(type default)
			)
			(layer "B.Fab")
		)
		(pad "1" smd rect
			(at 0.889 0 180)
			(size 1.016 1.27)
			(layers "B.Cu" "B.Mask" "B.Paste")
			(net "P0V9_CPU0_RT1_2A")
		)
		(pad "2" smd rect
			(at -0.889 0 180)
			(size 1.016 1.27)
			(layers "B.Cu" "B.Mask" "B.Paste")
			(net "GND")
		)
	)
	(footprint ""
		(layer "B.Cu")
		(at 415.569654 -170.48988 90)
		(property "Reference" "PC597"
			(at 5.924804 -1.286002 270)
			(unlocked yes)
			(layer "B.SilkS")
			(effects
				(font
					(size 0.7874 0.5842)
					(thickness 0.1524)
				)
				(justify left mirror)
			)
		)
		(property "Value" ""
			(at 0 0 90)
			(layer "B.Fab")
			(effects
				(font
					(size 1.27 1.27)
				)
				(justify mirror)
			)
		)
		(duplicate_pad_numbers_are_jumpers no)
		(fp_line
			(start 4.533392 -2.249932)
			(end -4.533392 -2.249932)
			(stroke
				(width 0.1524)
				(type default)
			)
			(layer "B.SilkS")
		)
		(fp_line
			(start -4.533392 -2.249932)
			(end -4.533392 2.249932)
			(stroke
				(width 0.1524)
				(type default)
			)
			(layer "B.SilkS")
		)
		(fp_line
			(start 4.533392 2.249932)
			(end 4.533392 -2.249932)
			(stroke
				(width 0.1524)
				(type default)
			)
			(layer "B.SilkS")
		)
		(fp_line
			(start -4.533392 2.249932)
			(end 4.533392 2.249932)
			(stroke
				(width 0.1524)
				(type default)
			)
			(layer "B.SilkS")
		)
		(fp_rect
			(start 4.533392 -2.326132)
			(end 5.39242 2.326132)
			(stroke
				(width 0)
				(type default)
			)
			(fill yes)
			(layer "B.SilkS")
		)
		(fp_line
			(start 3.750056 -2.249932)
			(end -3.750056 -2.249932)
			(stroke
				(width 0.1)
				(type default)
			)
			(layer "B.Fab")
		)
		(fp_line
			(start -3.750056 -2.249932)
			(end -3.750056 2.249932)
			(stroke
				(width 0.1)
				(type default)
			)
			(layer "B.Fab")
		)
		(fp_line
			(start 3.750056 2.249932)
			(end 3.750056 -2.249932)
			(stroke
				(width 0.1)
				(type default)
			)
			(layer "B.Fab")
		)
		(fp_line
			(start -3.750056 2.249932)
			(end 3.750056 2.249932)
			(stroke
				(width 0.1)
				(type default)
			)
			(layer "B.Fab")
		)
		(fp_text user "+"
			(at 6.322314 0.786384 0)
			(unlocked yes)
			(layer "B.SilkS")
			(effects
				(font
					(size 1.905 1.4224)
					(thickness 0.1524)
				)
				(justify left mirror)
			)
		)
		(fp_text user "-"
			(at -4.582668 1.44018 90)
			(unlocked yes)
			(layer "B.SilkS")
			(effects
				(font
					(size 1.905 1.4224)
					(thickness 0.1524)
				)
				(justify left mirror)
			)
		)
		(fp_text user "-"
			(at -4.8514 -0.14605 90)
			(unlocked yes)
			(layer "B.Fab")
			(effects
				(font
					(size 1.905 1.4224)
					(thickness 0.1524)
				)
				(justify left mirror)
			)
		)
		(fp_text user "+"
			(at 6.322314 0.786384 0)
			(unlocked yes)
			(layer "B.Fab")
			(effects
				(font
					(size 1.905 1.4224)
					(thickness 0.1524)
				)
				(justify left mirror)
			)
		)
		(pad "1" smd rect
			(at 3.199892 0 270)
			(size 2.413 2.8194)
			(layers "B.Cu" "B.Mask" "B.Paste")
			(net "PVDDCR_SOC_P0")
		)
		(pad "2" smd rect
			(at -3.199892 0 270)
			(size 2.413 2.8194)
			(layers "B.Cu" "B.Mask" "B.Paste")
			(net "GND")
		)
	)
	(footprint ""
		(layer "B.Cu")
		(at 378.878592 -395.148562 90)
		(property "Reference" "C1004"
			(at 0 0 90)
			(layer "B.SilkS")
			(hide yes)
			(effects
				(font
					(size 1.27 1.27)
				)
				(justify mirror)
			)
		)
		(property "Value" ""
			(at 0 0 90)
			(layer "B.Fab")
			(effects
				(font
					(size 1.27 1.27)
				)
				(justify mirror)
			)
		)
		(duplicate_pad_numbers_are_jumpers no)
		(fp_line
			(start 0.299974 -0.150114)
			(end -0.299974 -0.150114)
			(stroke
				(width 0.1)
				(type default)
			)
			(layer "B.Fab")
		)
		(fp_line
			(start -0.299974 -0.150114)
			(end -0.299974 0.150114)
			(stroke
				(width 0.1)
				(type default)
			)
			(layer "B.Fab")
		)
		(fp_line
			(start 0.299974 0.150114)
			(end 0.299974 -0.150114)
			(stroke
				(width 0.1)
				(type default)
			)
			(layer "B.Fab")
		)
		(fp_line
			(start -0.299974 0.150114)
			(end 0.299974 0.150114)
			(stroke
				(width 0.1)
				(type default)
			)
			(layer "B.Fab")
		)
		(pad "1" smd rect
			(at 0.2667 0 270)
			(size 0.3048 0.381)
			(layers "B.Cu" "B.Mask" "B.Paste")
			(net "P1V8_CPU0_RT3_1A")
		)
		(pad "2" smd rect
			(at -0.2667 0 270)
			(size 0.3048 0.381)
			(layers "B.Cu" "B.Mask" "B.Paste")
			(net "GND")
		)
	)
	(footprint ""
		(layer "B.Cu")
		(at 377.691142 -398.942052 90)
		(property "Reference" "C1044"
			(at 0 0 90)
			(layer "B.SilkS")
			(hide yes)
			(effects
				(font
					(size 1.27 1.27)
				)
				(justify mirror)
			)
		)
		(property "Value" ""
			(at 0 0 90)
			(layer "B.Fab")
			(effects
				(font
					(size 1.27 1.27)
				)
				(justify mirror)
			)
		)
		(duplicate_pad_numbers_are_jumpers no)
		(fp_line
			(start 0.7874 -0.4064)
			(end -0.7874 -0.4064)
			(stroke
				(width 0.1524)
				(type default)
			)
			(layer "B.SilkS")
		)
		(fp_line
			(start -0.7874 -0.4064)
			(end -0.7874 0.4064)
			(stroke
				(width 0.1524)
				(type default)
			)
			(layer "B.SilkS")
		)
		(fp_line
			(start 0.7874 0.4064)
			(end 0.7874 -0.4064)
			(stroke
				(width 0.1524)
				(type default)
			)
			(layer "B.SilkS")
		)
		(fp_line
			(start -0.7874 0.4064)
			(end 0.7874 0.4064)
			(stroke
				(width 0.1524)
				(type default)
			)
			(layer "B.SilkS")
		)
		(fp_line
			(start 0.67945 -0.305054)
			(end 0.12065 -0.305054)
			(stroke
				(width 0.1)
				(type default)
			)
			(layer "B.Fab")
		)
		(fp_line
			(start 0.12065 -0.305054)
			(end 0.12065 -0.2794)
			(stroke
				(width 0.1)
				(type default)
			)
			(layer "B.Fab")
		)
		(fp_line
			(start -0.12065 -0.3048)
			(end -0.67945 -0.3048)
			(stroke
				(width 0.1)
				(type default)
			)
			(layer "B.Fab")
		)
		(fp_line
			(start -0.67945 -0.3048)
			(end -0.67945 0.3048)
			(stroke
				(width 0.1)
				(type default)
			)
			(layer "B.Fab")
		)
		(fp_line
			(start 0.12065 -0.2794)
			(end -0.12065 -0.2794)
			(stroke
				(width 0.1)
				(type default)
			)
			(layer "B.Fab")
		)
		(fp_line
			(start -0.12065 -0.2794)
			(end -0.12065 -0.3048)
			(stroke
				(width 0.1)
				(type default)
			)
			(layer "B.Fab")
		)
		(fp_line
			(start 0.12065 0.2794)
			(end 0.12065 0.3048)
			(stroke
				(width 0.1)
				(type default)
			)
			(layer "B.Fab")
		)
		(fp_line
			(start -0.120396 0.2794)
			(end 0.12065 0.2794)
			(stroke
				(width 0.1)
				(type default)
			)
			(layer "B.Fab")
		)
		(fp_line
			(start 0.67945 0.3048)
			(end 0.67945 -0.305054)
			(stroke
				(width 0.1)
				(type default)
			)
			(layer "B.Fab")
		)
		(fp_line
			(start 0.12065 0.3048)
			(end 0.67945 0.3048)
			(stroke
				(width 0.1)
				(type default)
			)
			(layer "B.Fab")
		)
		(fp_line
			(start -0.120396 0.3048)
			(end -0.120396 0.2794)
			(stroke
				(width 0.1)
				(type default)
			)
			(layer "B.Fab")
		)
		(fp_line
			(start -0.67945 0.3048)
			(end -0.120396 0.3048)
			(stroke
				(width 0.1)
				(type default)
			)
			(layer "B.Fab")
		)
		(pad "1" smd circle
			(at 0.40005 0 270)
			(size 0 0)
			(layers "B.Cu" "B.Mask" "B.Paste")
			(net "P0V9_CPU0_RT_2D")
		)
		(pad "2" smd circle
			(at -0.40005 0 270)
			(size 0 0)
			(layers "B.Cu" "B.Mask" "B.Paste")
			(net "GND")
		)
	)
	(footprint ""
		(layer "B.Cu")
		(at 179.997608 -126.833376 90)
		(property "Reference" "R242"
			(at 0 0 90)
			(layer "B.SilkS")
			(hide yes)
			(effects
				(font
					(size 1.27 1.27)
				)
				(justify mirror)
			)
		)
		(property "Value" ""
			(at 0 0 90)
			(layer "B.Fab")
			(effects
				(font
					(size 1.27 1.27)
				)
				(justify mirror)
			)
		)
		(duplicate_pad_numbers_are_jumpers no)
		(fp_line
			(start 0.7874 -0.4064)
			(end -0.7874 -0.4064)
			(stroke
				(width 0.1524)
				(type default)
			)
			(layer "B.SilkS")
		)
		(fp_line
			(start -0.7874 -0.4064)
			(end -0.7874 0.4064)
			(stroke
				(width 0.1524)
				(type default)
			)
			(layer "B.SilkS")
		)
		(fp_line
			(start 0.7874 0.4064)
			(end 0.7874 -0.4064)
			(stroke
				(width 0.1524)
				(type default)
			)
			(layer "B.SilkS")
		)
		(fp_line
			(start -0.7874 0.4064)
			(end 0.7874 0.4064)
			(stroke
				(width 0.1524)
				(type default)
			)
			(layer "B.SilkS")
		)
		(fp_line
			(start 0.67945 -0.305054)
			(end 0.12065 -0.305054)
			(stroke
				(width 0.1)
				(type default)
			)
			(layer "B.Fab")
		)
		(fp_line
			(start 0.12065 -0.305054)
			(end 0.12065 -0.2794)
			(stroke
				(width 0.1)
				(type default)
			)
			(layer "B.Fab")
		)
		(fp_line
			(start -0.12065 -0.3048)
			(end -0.67945 -0.3048)
			(stroke
				(width 0.1)
				(type default)
			)
			(layer "B.Fab")
		)
		(fp_line
			(start -0.67945 -0.3048)
			(end -0.67945 0.3048)
			(stroke
				(width 0.1)
				(type default)
			)
			(layer "B.Fab")
		)
		(fp_line
			(start 0.12065 -0.2794)
			(end -0.12065 -0.2794)
			(stroke
				(width 0.1)
				(type default)
			)
			(layer "B.Fab")
		)
		(fp_line
			(start -0.12065 -0.2794)
			(end -0.12065 -0.3048)
			(stroke
				(width 0.1)
				(type default)
			)
			(layer "B.Fab")
		)
		(fp_line
			(start 0.12065 0.2794)
			(end 0.12065 0.3048)
			(stroke
				(width 0.1)
				(type default)
			)
			(layer "B.Fab")
		)
		(fp_line
			(start -0.120396 0.2794)
			(end 0.12065 0.2794)
			(stroke
				(width 0.1)
				(type default)
			)
			(layer "B.Fab")
		)
		(fp_line
			(start 0.67945 0.3048)
			(end 0.67945 -0.305054)
			(stroke
				(width 0.1)
				(type default)
			)
			(layer "B.Fab")
		)
		(fp_line
			(start 0.12065 0.3048)
			(end 0.67945 0.3048)
			(stroke
				(width 0.1)
				(type default)
			)
			(layer "B.Fab")
		)
		(fp_line
			(start -0.120396 0.3048)
			(end -0.120396 0.2794)
			(stroke
				(width 0.1)
				(type default)
			)
			(layer "B.Fab")
		)
		(fp_line
			(start -0.67945 0.3048)
			(end -0.120396 0.3048)
			(stroke
				(width 0.1)
				(type default)
			)
			(layer "B.Fab")
		)
		(pad "1" smd circle
			(at 0.40005 0 270)
			(size 0 0)
			(layers "B.Cu" "B.Mask" "B.Paste")
			(net "PWRGD_CPU0_PWROK")
		)
		(pad "2" smd circle
			(at -0.40005 0 270)
			(size 0 0)
			(layers "B.Cu" "B.Mask" "B.Paste")
			(net "FM_PWRGD_CPU0_PWROK")
		)
	)
	(footprint ""
		(layer "B.Cu")
		(at 181.525164 -23.655782 -90)
		(property "Reference" "R1319"
			(at 0 0 90)
			(layer "B.SilkS")
			(hide yes)
			(effects
				(font
					(size 1.27 1.27)
				)
				(justify mirror)
			)
		)
		(property "Value" ""
			(at 0 0 90)
			(layer "B.Fab")
			(effects
				(font
					(size 1.27 1.27)
				)
				(justify mirror)
			)
		)
		(duplicate_pad_numbers_are_jumpers no)
		(fp_line
			(start -0.7874 0.4064)
			(end 0.7874 0.4064)
			(stroke
				(width 0.1524)
				(type default)
			)
			(layer "B.SilkS")
		)
		(fp_line
			(start 0.7874 0.4064)
			(end 0.7874 -0.4064)
			(stroke
				(width 0.1524)
				(type default)
			)
			(layer "B.SilkS")
		)
		(fp_line
			(start -0.7874 -0.4064)
			(end -0.7874 0.4064)
			(stroke
				(width 0.1524)
				(type default)
			)
			(layer "B.SilkS")
		)
		(fp_line
			(start 0.7874 -0.4064)
			(end -0.7874 -0.4064)
			(stroke
				(width 0.1524)
				(type default)
			)
			(layer "B.SilkS")
		)
		(fp_line
			(start -0.67945 0.3048)
			(end -0.120396 0.3048)
			(stroke
				(width 0.1)
				(type default)
			)
			(layer "B.Fab")
		)
		(fp_line
			(start -0.120396 0.3048)
			(end -0.120396 0.2794)
			(stroke
				(width 0.1)
				(type default)
			)
			(layer "B.Fab")
		)
		(fp_line
			(start 0.12065 0.3048)
			(end 0.67945 0.3048)
			(stroke
				(width 0.1)
				(type default)
			)
			(layer "B.Fab")
		)
		(fp_line
			(start 0.67945 0.3048)
			(end 0.67945 -0.305054)
			(stroke
				(width 0.1)
				(type default)
			)
			(layer "B.Fab")
		)
		(fp_line
			(start -0.120396 0.2794)
			(end 0.12065 0.2794)
			(stroke
				(width 0.1)
				(type default)
			)
			(layer "B.Fab")
		)
		(fp_line
			(start 0.12065 0.2794)
			(end 0.12065 0.3048)
			(stroke
				(width 0.1)
				(type default)
			)
			(layer "B.Fab")
		)
		(fp_line
			(start -0.12065 -0.2794)
			(end -0.12065 -0.3048)
			(stroke
				(width 0.1)
				(type default)
			)
			(layer "B.Fab")
		)
		(fp_line
			(start 0.12065 -0.2794)
			(end -0.12065 -0.2794)
			(stroke
				(width 0.1)
				(type default)
			)
			(layer "B.Fab")
		)
		(fp_line
			(start -0.67945 -0.3048)
			(end -0.67945 0.3048)
			(stroke
				(width 0.1)
				(type default)
			)
			(layer "B.Fab")
		)
		(fp_line
			(start -0.12065 -0.3048)
			(end -0.67945 -0.3048)
			(stroke
				(width 0.1)
				(type default)
			)
			(layer "B.Fab")
		)
		(fp_line
			(start 0.12065 -0.305054)
			(end 0.12065 -0.2794)
			(stroke
				(width 0.1)
				(type default)
			)
			(layer "B.Fab")
		)
		(fp_line
			(start 0.67945 -0.305054)
			(end 0.12065 -0.305054)
			(stroke
				(width 0.1)
				(type default)
			)
			(layer "B.Fab")
		)
		(pad "1" smd circle
			(at 0.40005 0 90)
			(size 0 0)
			(layers "B.Cu" "B.Mask" "B.Paste")
			(net "SMB_CPU0_CPU1_APML_SCL")
		)
		(pad "2" smd circle
			(at -0.40005 0 90)
			(size 0 0)
			(layers "B.Cu" "B.Mask" "B.Paste")
			(net "P3V3_AUX")
		)
	)
)
